# TIMECARD (Time Appliance Project (Time Card)) — schematic netlist excerpt (pin names and nets, part order shuffled) for the footprints in the layout excerpt that follows; sources: Cadence DE-HDL packaged netlist, KiCad conversion of R4006-B0001-02_R01.brd

R72  RESISTOR  33OHM 1%  pkg SMC_0402R_H016  page 19 : \1\ = BF_ICP10100_I2C_SDA ; \2\ = R_ICP10100_I2C_SDA
R489  RESISTOR  3.92KOHM 1%  pkg SMC_0402R  page 33 : \1\ = UNNAMED_525_ISL80101IRAJZDFN10_ ; \2\ = SG

(kicad_pcb
	(version 20260206)
	(generator "pcbnew")
	(generator_version "10.0")
	(general
		(thickness 1.6)
		(legacy_teardrops no)
	)
	(paper "A4")
	(title_block
		(title "timecard-production-celestica-r4006 — R4006-B0001-02_R01.brd")
		(comment 1 "Time Appliance Project (Time Card) / footprints 259-260 of 1113")
	)
	(layers
		(0 "F.Cu" signal "TOP")
		(4 "In1.Cu" signal "L02_GND1")
		(6 "In2.Cu" signal "L03_SIG1")
		(8 "In3.Cu" signal "L04_GND2")
		(10 "In4.Cu" signal "L05_VCC1")
		(12 "In5.Cu" signal "L06_VCC2")
		(14 "In6.Cu" signal "L07_GND3")
		(16 "In7.Cu" signal "L08_SIG2")
		(18 "In8.Cu" signal "L09_GND4")
		(2 "B.Cu" signal "BOTTOM")
		(9 "F.Adhes" user "F.Adhesive")
		(11 "B.Adhes" user "B.Adhesive")
		(13 "F.Paste" user "Package Geometry/Pastemask Top")
		(15 "B.Paste" user "Package Geometry/Pastemask Bottom")
		(5 "F.SilkS" user "Ref Des/Silkscreen Top")
		(7 "B.SilkS" user "Ref Des/Silkscreen Bottom")
		(1 "F.Mask" user "Board Geometry/Soldermask Top")
		(3 "B.Mask" user "Board Geometry/Soldermask Bottom")
		(17 "Dwgs.User" user "User.Drawings")
		(19 "Cmts.User" user "User.Comments")
		(21 "Eco1.User" user "User.Eco1")
		(23 "Eco2.User" user "User.Eco2")
		(25 "Edge.Cuts" user "Board Geometry/Outline")
		(27 "Margin" user)
		(31 "F.CrtYd" user "Package Geometry/Place Bound Top")
		(29 "B.CrtYd" user "Package Geometry/Place Bound Bottom")
		(35 "F.Fab" user "Ref Des/Assembly Top")
		(33 "B.Fab" user "Ref Des/Assembly Bottom")
	)
	(footprint ""
		(layer "F.Cu")
		(at 38.227 -74.93 180)
		(property "Reference" "R489"
			(at -0.508 -1.30937 0)
			(unlocked yes)
			(layer "F.SilkS")
			(effects
				(font
					(size 0.7874 0.5842)
					(thickness 0.1524)
				)
			)
		)
		(property "Value" "VAL*"
			(at 0.0508 2.245106 180)
			(unlocked yes)
			(layer "F.Fab")
			(hide yes)
			(effects
				(font
					(size 0.7874 0.5842)
					(thickness 0.1524)
				)
			)
		)
		(property "User Part Number" "PARTNUM*"
			(at 0.0762 4.302506 180)
			(unlocked yes)
			(layer "Cmts.User")
			(hide yes)
			(effects
				(font
					(size 0.7874 0.5842)
					(thickness 0.1524)
				)
			)
		)
		(property "Device Type" "RESISTOR-G155-03921-01,3.92KOHA"
			(at 0.0762 1.254506 180)
			(unlocked yes)
			(layer "F.Fab")
			(hide yes)
			(effects
				(font
					(size 0.7874 0.5842)
					(thickness 0.1524)
				)
			)
		)
		(property "Tolerance" "TOL*"
			(at 0.0508 3.261106 180)
			(unlocked yes)
			(layer "Cmts.User")
			(hide yes)
			(effects
				(font
					(size 0.7874 0.5842)
					(thickness 0.1524)
				)
			)
		)
		(duplicate_pad_numbers_are_jumpers no)
		(fp_line
			(start 1.143 0.5588)
			(end 1.143 -0.5588)
			(stroke
				(width 0.1)
				(type default)
			)
			(layer "F.SilkS")
		)
		(fp_line
			(start 1.143 -0.5588)
			(end -1.143 -0.5588)
			(stroke
				(width 0.1)
				(type default)
			)
			(layer "F.SilkS")
		)
		(fp_line
			(start -1.143 0.5588)
			(end 1.143 0.5588)
			(stroke
				(width 0.1)
				(type default)
			)
			(layer "F.SilkS")
		)
		(fp_line
			(start -1.143 -0.5588)
			(end -1.143 0.5588)
			(stroke
				(width 0.1)
				(type default)
			)
			(layer "F.SilkS")
		)
		(fp_poly
			(pts
				(xy -1.143 0.5588) (xy 1.143 0.5588) (xy 1.143 -0.5588) (xy -1.143 -0.5588)
			)
			(stroke
				(width 0)
				(type default)
			)
			(fill no)
			(layer "F.CrtYd")
		)
		(fp_line
			(start 0.508 0.3048)
			(end 0.508 -0.3048)
			(stroke
				(width 0.1)
				(type default)
			)
			(layer "F.Fab")
		)
		(fp_line
			(start 0.508 -0.3048)
			(end -0.508 -0.3048)
			(stroke
				(width 0.1)
				(type default)
			)
			(layer "F.Fab")
		)
		(fp_line
			(start -0.508 0.3048)
			(end 0.508 0.3048)
			(stroke
				(width 0.1)
				(type default)
			)
			(layer "F.Fab")
		)
		(fp_line
			(start -0.508 -0.3048)
			(end -0.508 0.3048)
			(stroke
				(width 0.1)
				(type default)
			)
			(layer "F.Fab")
		)
		(pad "1" smd rect
			(at -0.5334 0 180)
			(size 0.7112 0.6096)
			(layers "F.Cu" "F.Mask" "F.Paste")
			(net "UNNAMED_525_ISL80101IRAJZDFN10_")
		)
		(pad "2" smd rect
			(at 0.5334 0 180)
			(size 0.7112 0.6096)
			(layers "F.Cu" "F.Mask" "F.Paste")
			(net "SG")
		)
		(zone
			(layer "F.Cu")
			(hatch none 0.5)
			(connect_pads
				(clearance 0)
			)
			(min_thickness 0.25)
			(keepout
				(tracks allowed)
				(vias not_allowed)
				(pads allowed)
				(copperpour not_allowed)
				(footprints allowed)
			)
			(placement
				(enabled no)
				(sheetname "")
			)
			(fill
				(thermal_gap 0.5)
				(thermal_bridge_width 0.5)
				(island_removal_mode 0)
			)
			(polygon
				(pts
					(xy 38.3032 -75.2348) (xy 38.1508 -75.2348) (xy 38.1508 -74.6252) (xy 38.3032 -74.6252)
				)
			)
		)
		(zone
			(layer "F.Cu")
			(hatch none 0.5)
			(connect_pads
				(clearance 0)
			)
			(min_thickness 0.25)
			(keepout
				(tracks not_allowed)
				(vias allowed)
				(pads allowed)
				(copperpour not_allowed)
				(footprints allowed)
			)
			(placement
				(enabled no)
				(sheetname "")
			)
			(fill
				(thermal_gap 0.5)
				(thermal_bridge_width 0.5)
				(island_removal_mode 0)
			)
			(polygon
				(pts
					(xy 38.3032 -75.2348) (xy 38.1508 -75.2348) (xy 38.1508 -74.6252) (xy 38.3032 -74.6252)
				)
			)
		)
	)
	(footprint ""
		(layer "F.Cu")
		(at 16.852392 -67.6656)
		(property "Reference" "R72"
			(at -1.993392 -0.50165 0)
			(unlocked yes)
			(layer "F.SilkS")
			(effects
				(font
					(size 0.635 0.4064)
					(thickness 0.1524)
				)
			)
		)
		(property "Value" "VAL*"
			(at 0.02032 2.13233 0)
			(unlocked yes)
			(layer "F.Fab")
			(hide yes)
			(effects
				(font
					(size 0.7874 0.5842)
					(thickness 0.1524)
				)
			)
		)
		(property "Tolerance" "TOL*"
			(at 0.044704 3.05435 0)
			(unlocked yes)
			(layer "Cmts.User")
			(hide yes)
			(effects
				(font
					(size 0.7874 0.5842)
					(thickness 0.1524)
				)
			)
		)
		(property "User Part Number" "PARTNUM*"
			(at 0.02032 4.024884 0)
			(unlocked yes)
			(layer "Cmts.User")
			(hide yes)
			(effects
				(font
					(size 0.7874 0.5842)
					(thickness 0.1524)
				)
			)
		)
		(property "Device Type" "RESISTOR-G155-133R0-01,33OHM,1%"
			(at 0.008382 1.210564 0)
			(unlocked yes)
			(layer "F.Fab")
			(hide yes)
			(effects
				(font
					(size 0.7874 0.5842)
					(thickness 0.1524)
				)
			)
		)
		(duplicate_pad_numbers_are_jumpers no)
		(fp_line
			(start -1.143 -0.5588)
			(end -1.143 0.5588)
			(stroke
				(width 0.1)
				(type default)
			)
			(layer "F.SilkS")
		)
		(fp_line
			(start -1.143 0.5588)
			(end 1.143 0.5588)
			(stroke
				(width 0.1)
				(type default)
			)
			(layer "F.SilkS")
		)
		(fp_line
			(start 1.143 -0.5588)
			(end -1.143 -0.5588)
			(stroke
				(width 0.1)
				(type default)
			)
			(layer "F.SilkS")
		)
		(fp_line
			(start 1.143 0.5588)
			(end 1.143 -0.5588)
			(stroke
				(width 0.1)
				(type default)
			)
			(layer "F.SilkS")
		)
		(fp_rect
			(start -1.143 -0.5588)
			(end 1.143 0.5588)
			(stroke
				(width 0)
				(type default)
			)
			(fill no)
			(layer "F.CrtYd")
		)
		(fp_line
			(start -0.508 -0.3048)
			(end -0.508 0.3048)
			(stroke
				(width 0.1)
				(type default)
			)
			(layer "F.Fab")
		)
		(fp_line
			(start -0.508 0.3048)
			(end 0.508 0.3048)
			(stroke
				(width 0.1)
				(type default)
			)
			(layer "F.Fab")
		)
		(fp_line
			(start 0.508 -0.3048)
			(end -0.508 -0.3048)
			(stroke
				(width 0.1)
				(type default)
			)
			(layer "F.Fab")
		)
		(fp_line
			(start 0.508 0.3048)
			(end 0.508 -0.3048)
			(stroke
				(width 0.1)
				(type default)
			)
			(layer "F.Fab")
		)
		(pad "1" smd rect
			(at -0.5334 0)
			(size 0.7112 0.6096)
			(layers "F.Cu" "F.Mask" "F.Paste")
			(net "BF_ICP10100_I2C_SDA")
		)
		(pad "2" smd rect
			(at 0.5334 0)
			(size 0.7112 0.6096)
			(layers "F.Cu" "F.Mask" "F.Paste")
			(net "R_ICP10100_I2C_SDA")
		)
		(zone
			(layer "F.Cu")
			(hatch none 0.5)
			(connect_pads
				(clearance 0)
			)
			(min_thickness 0.25)
			(keepout
				(tracks allowed)
				(vias not_allowed)
				(pads allowed)
				(copperpour not_allowed)
				(footprints allowed)
			)
			(placement
				(enabled no)
				(sheetname "")
			)
			(fill
				(thermal_gap 0.5)
				(thermal_bridge_width 0.5)
				(island_removal_mode 0)
			)
			(polygon
				(pts
					(xy 16.776192 -67.9704) (xy 16.776192 -67.3608) (xy 16.928592 -67.3608) (xy 16.928592 -67.9704)
				)
			)
		)
	)
)
